FILE_TYPE=LIBRARY_PARTS;
TIME=' Created/Modified on Tue Mar 28 17:46:16 2006' ;
primitive 'GND_HOLE';
  pin
    'GND3':
      PIN_NUMBER='(3)';
      PINUSE='POWER';
    'GND2':
      PIN_NUMBER='(2)';
      PINUSE='POWER';
    'GND9':
      PIN_NUMBER='(9)';
      PINUSE='POWER';
    'GND8':
      PIN_NUMBER='(8)';
      PINUSE='POWER';
    'GND7':
      PIN_NUMBER='(7)';
      PINUSE='POWER';
    'GND6':
      PIN_NUMBER='(6)';
      PINUSE='POWER';
    'GND5':
      PIN_NUMBER='(5)';
      PINUSE='POWER';
    'GND4':
      PIN_NUMBER='(4)';
      PINUSE='POWER';
  end_pin;
  body
    NC_PINS='(1)';
    CLASS='DISCRETE';
    PART_NAME='GND_HOLE';
    PHYS_DES_PREFIX='H';
  end_body;
end_primitive;
END.
